(kicad_pcb
	(version 20260206)
	(generator "pcbnew")
	(generator_version "10.0")
	(general
		(thickness 1.6)
		(legacy_teardrops no)
	)
	(paper "A4")
	(title_block
		(title "9054_F0T_PDB_BD_GPU_F_V04_1213_1550_OCP.brd")
		(comment 1 "Grand Teton / footprints 570-574 of 608")
	)
	(layers
		(0 "F.Cu" signal "TOP")
		(4 "In1.Cu" signal "GND")
		(6 "In2.Cu" signal "IN1")
		(8 "In3.Cu" signal "GND1")
		(10 "In4.Cu" signal "VCC")
		(12 "In5.Cu" signal "VCC1")
		(14 "In6.Cu" signal "GND2")
		(16 "In7.Cu" signal "IN2")
		(18 "In8.Cu" signal "GND3")
		(2 "B.Cu" signal "BOTTOM")
		(9 "F.Adhes" user "F.Adhesive")
		(11 "B.Adhes" user "B.Adhesive")
		(13 "F.Paste" user "Package Geometry/Pastemask Top")
		(15 "B.Paste" user "Package Geometry/Pastemask Bottom")
		(5 "F.SilkS" user "Ref Des/Silkscreen Top")
		(7 "B.SilkS" user "Ref Des/Silkscreen Bottom")
		(1 "F.Mask" user "Board Geometry/Soldermask Top")
		(3 "B.Mask" user "Board Geometry/Soldermask Bottom")
		(17 "Dwgs.User" user "User.Drawings")
		(19 "Cmts.User" user "User.Comments")
		(21 "Eco1.User" user "User.Eco1")
		(23 "Eco2.User" user "User.Eco2")
		(25 "Edge.Cuts" user "Board Geometry/Outline")
		(27 "Margin" user)
		(31 "F.CrtYd" user "Package Geometry/Place Bound Top")
		(29 "B.CrtYd" user "Package Geometry/Place Bound Bottom")
		(35 "F.Fab" user "Ref Des/Assembly Top")
		(33 "B.Fab" user "Ref Des/Assembly Bottom")
	)
	(footprint ""
		(layer "B.Cu")
		(at 426.593 -36.957)
		(property "Reference" "R5933"
			(at 0 0 0)
			(layer "B.SilkS")
			(hide yes)
			(effects
				(font
					(size 1.27 1.27)
				)
				(justify mirror)
			)
		)
		(property "Value" ""
			(at 0 0 0)
			(layer "B.Fab")
			(effects
				(font
					(size 1.27 1.27)
				)
				(justify mirror)
			)
		)
		(duplicate_pad_numbers_are_jumpers no)
		(fp_line
			(start -0.7874 -0.4064)
			(end -0.7874 0.4064)
			(stroke
				(width 0.1524)
				(type default)
			)
			(layer "B.SilkS")
		)
		(fp_line
			(start -0.7874 0.4064)
			(end 0.7874 0.4064)
			(stroke
				(width 0.1524)
				(type default)
			)
			(layer "B.SilkS")
		)
		(fp_line
			(start 0.7874 -0.4064)
			(end -0.7874 -0.4064)
			(stroke
				(width 0.1524)
				(type default)
			)
			(layer "B.SilkS")
		)
		(fp_line
			(start 0.7874 0.4064)
			(end 0.7874 -0.4064)
			(stroke
				(width 0.1524)
				(type default)
			)
			(layer "B.SilkS")
		)
		(fp_line
			(start -0.67945 -0.3048)
			(end -0.67945 0.3048)
			(stroke
				(width 0.1)
				(type default)
			)
			(layer "B.Fab")
		)
		(fp_line
			(start -0.67945 0.3048)
			(end -0.120396 0.3048)
			(stroke
				(width 0.1)
				(type default)
			)
			(layer "B.Fab")
		)
		(fp_line
			(start -0.12065 -0.3048)
			(end -0.67945 -0.3048)
			(stroke
				(width 0.1)
				(type default)
			)
			(layer "B.Fab")
		)
		(fp_line
			(start -0.12065 -0.2794)
			(end -0.12065 -0.3048)
			(stroke
				(width 0.1)
				(type default)
			)
			(layer "B.Fab")
		)
		(fp_line
			(start -0.120396 0.2794)
			(end 0.12065 0.2794)
			(stroke
				(width 0.1)
				(type default)
			)
			(layer "B.Fab")
		)
		(fp_line
			(start -0.120396 0.3048)
			(end -0.120396 0.2794)
			(stroke
				(width 0.1)
				(type default)
			)
			(layer "B.Fab")
		)
		(fp_line
			(start 0.12065 -0.305054)
			(end 0.12065 -0.2794)
			(stroke
				(width 0.1)
				(type default)
			)
			(layer "B.Fab")
		)
		(fp_line
			(start 0.12065 -0.2794)
			(end -0.12065 -0.2794)
			(stroke
				(width 0.1)
				(type default)
			)
			(layer "B.Fab")
		)
		(fp_line
			(start 0.12065 0.2794)
			(end 0.12065 0.3048)
			(stroke
				(width 0.1)
				(type default)
			)
			(layer "B.Fab")
		)
		(fp_line
			(start 0.12065 0.3048)
			(end 0.67945 0.3048)
			(stroke
				(width 0.1)
				(type default)
			)
			(layer "B.Fab")
		)
		(fp_line
			(start 0.67945 -0.305054)
			(end 0.12065 -0.305054)
			(stroke
				(width 0.1)
				(type default)
			)
			(layer "B.Fab")
		)
		(fp_line
			(start 0.67945 0.3048)
			(end 0.67945 -0.305054)
			(stroke
				(width 0.1)
				(type default)
			)
			(layer "B.Fab")
		)
		(pad "1" smd circle
			(at 0.40005 0 180)
			(size 0 0)
			(layers "B.Cu" "B.Mask" "B.Paste")
			(net "SMB_PDB_MISC_SCL")
		)
		(pad "2" smd circle
			(at -0.40005 0 180)
			(size 0 0)
			(layers "B.Cu" "B.Mask" "B.Paste")
			(net "SMB_IOEXP_2_SCL")
		)
	)
	(footprint ""
		(layer "B.Cu")
		(at 177.592736 -80.391 90)
		(property "Reference" "PR7022"
			(at 0 0 90)
			(layer "B.SilkS")
			(hide yes)
			(effects
				(font
					(size 1.27 1.27)
				)
				(justify mirror)
			)
		)
		(property "Value" ""
			(at 0 0 90)
			(layer "B.Fab")
			(effects
				(font
					(size 1.27 1.27)
				)
				(justify mirror)
			)
		)
		(duplicate_pad_numbers_are_jumpers no)
		(fp_line
			(start 1.651 -0.8382)
			(end -1.651 -0.8382)
			(stroke
				(width 0.1524)
				(type default)
			)
			(layer "B.SilkS")
		)
		(fp_line
			(start -1.651 -0.8382)
			(end -1.651 0.8382)
			(stroke
				(width 0.1524)
				(type default)
			)
			(layer "B.SilkS")
		)
		(fp_line
			(start 1.651 0.8382)
			(end 1.651 -0.8382)
			(stroke
				(width 0.1524)
				(type default)
			)
			(layer "B.SilkS")
		)
		(fp_line
			(start -1.651 0.8382)
			(end 1.651 0.8382)
			(stroke
				(width 0.1524)
				(type default)
			)
			(layer "B.SilkS")
		)
		(fp_line
			(start 1.559814 -0.7366)
			(end 1.559814 0.7366)
			(stroke
				(width 0.1)
				(type default)
			)
			(layer "B.Fab")
		)
		(fp_line
			(start 1.524 -0.7366)
			(end 1.559814 -0.7366)
			(stroke
				(width 0.1)
				(type default)
			)
			(layer "B.Fab")
		)
		(fp_line
			(start -1.524 -0.7366)
			(end 1.524 -0.7366)
			(stroke
				(width 0.1)
				(type default)
			)
			(layer "B.Fab")
		)
		(fp_line
			(start -1.560576 -0.7366)
			(end -1.524 -0.7366)
			(stroke
				(width 0.1)
				(type default)
			)
			(layer "B.Fab")
		)
		(fp_line
			(start 1.559814 0.7366)
			(end 1.524 0.7366)
			(stroke
				(width 0.1)
				(type default)
			)
			(layer "B.Fab")
		)
		(fp_line
			(start 1.524 0.7366)
			(end -1.524 0.7366)
			(stroke
				(width 0.1)
				(type default)
			)
			(layer "B.Fab")
		)
		(fp_line
			(start -1.524 0.7366)
			(end -1.560576 0.7366)
			(stroke
				(width 0.1)
				(type default)
			)
			(layer "B.Fab")
		)
		(fp_line
			(start -1.560576 0.7366)
			(end -1.560576 -0.7366)
			(stroke
				(width 0.1)
				(type default)
			)
			(layer "B.Fab")
		)
		(pad "1" smd rect
			(at 0.94996 0 90)
			(size 1.1176 1.3716)
			(layers "B.Cu" "B.Mask" "B.Paste")
			(net "P52V_HS2")
		)
		(pad "2" smd rect
			(at -0.94996 0 90)
			(size 1.1176 1.3716)
			(layers "B.Cu" "B.Mask" "B.Paste")
			(net "P52V_HS2_PWRGIN")
		)
	)
	(footprint ""
		(layer "B.Cu")
		(at 153.970736 -62.357 180)
		(property "Reference" "PR7010"
			(at 0 0 0)
			(layer "B.SilkS")
			(hide yes)
			(effects
				(font
					(size 1.27 1.27)
				)
				(justify mirror)
			)
		)
		(property "Value" ""
			(at 0 0 0)
			(layer "B.Fab")
			(effects
				(font
					(size 1.27 1.27)
				)
				(justify mirror)
			)
		)
		(duplicate_pad_numbers_are_jumpers no)
		(fp_line
			(start 0.7874 0.4064)
			(end 0.7874 -0.4064)
			(stroke
				(width 0.1524)
				(type default)
			)
			(layer "B.SilkS")
		)
		(fp_line
			(start 0.7874 -0.4064)
			(end -0.7874 -0.4064)
			(stroke
				(width 0.1524)
				(type default)
			)
			(layer "B.SilkS")
		)
		(fp_line
			(start -0.7874 0.4064)
			(end 0.7874 0.4064)
			(stroke
				(width 0.1524)
				(type default)
			)
			(layer "B.SilkS")
		)
		(fp_line
			(start -0.7874 -0.4064)
			(end -0.7874 0.4064)
			(stroke
				(width 0.1524)
				(type default)
			)
			(layer "B.SilkS")
		)
		(fp_line
			(start 0.67945 0.3048)
			(end 0.67945 -0.305054)
			(stroke
				(width 0.1)
				(type default)
			)
			(layer "B.Fab")
		)
		(fp_line
			(start 0.67945 -0.305054)
			(end 0.12065 -0.305054)
			(stroke
				(width 0.1)
				(type default)
			)
			(layer "B.Fab")
		)
		(fp_line
			(start 0.12065 0.3048)
			(end 0.67945 0.3048)
			(stroke
				(width 0.1)
				(type default)
			)
			(layer "B.Fab")
		)
		(fp_line
			(start 0.12065 0.2794)
			(end 0.12065 0.3048)
			(stroke
				(width 0.1)
				(type default)
			)
			(layer "B.Fab")
		)
		(fp_line
			(start 0.12065 -0.2794)
			(end -0.12065 -0.2794)
			(stroke
				(width 0.1)
				(type default)
			)
			(layer "B.Fab")
		)
		(fp_line
			(start 0.12065 -0.305054)
			(end 0.12065 -0.2794)
			(stroke
				(width 0.1)
				(type default)
			)
			(layer "B.Fab")
		)
		(fp_line
			(start -0.120396 0.3048)
			(end -0.120396 0.2794)
			(stroke
				(width 0.1)
				(type default)
			)
			(layer "B.Fab")
		)
		(fp_line
			(start -0.120396 0.2794)
			(end 0.12065 0.2794)
			(stroke
				(width 0.1)
				(type default)
			)
			(layer "B.Fab")
		)
		(fp_line
			(start -0.12065 -0.2794)
			(end -0.12065 -0.3048)
			(stroke
				(width 0.1)
				(type default)
			)
			(layer "B.Fab")
		)
		(fp_line
			(start -0.12065 -0.3048)
			(end -0.67945 -0.3048)
			(stroke
				(width 0.1)
				(type default)
			)
			(layer "B.Fab")
		)
		(fp_line
			(start -0.67945 0.3048)
			(end -0.120396 0.3048)
			(stroke
				(width 0.1)
				(type default)
			)
			(layer "B.Fab")
		)
		(fp_line
			(start -0.67945 -0.3048)
			(end -0.67945 0.3048)
			(stroke
				(width 0.1)
				(type default)
			)
			(layer "B.Fab")
		)
		(pad "1" smd circle
			(at 0.40005 0)
			(size 0 0)
			(layers "B.Cu" "B.Mask" "B.Paste")
			(net "P52V_HS2_FB")
		)
		(pad "2" smd circle
			(at -0.40005 0)
			(size 0 0)
			(layers "B.Cu" "B.Mask" "B.Paste")
			(net "GND1_FIELD_SIGNAL")
		)
	)
	(footprint ""
		(layer "B.Cu")
		(at 288.29 -92.075 -90)
		(property "Reference" "R5903"
			(at 0 0 90)
			(layer "B.SilkS")
			(hide yes)
			(effects
				(font
					(size 1.27 1.27)
				)
				(justify mirror)
			)
		)
		(property "Value" ""
			(at 0 0 90)
			(layer "B.Fab")
			(effects
				(font
					(size 1.27 1.27)
				)
				(justify mirror)
			)
		)
		(duplicate_pad_numbers_are_jumpers no)
		(fp_line
			(start -0.7874 0.4064)
			(end 0.7874 0.4064)
			(stroke
				(width 0.1524)
				(type default)
			)
			(layer "B.SilkS")
		)
		(fp_line
			(start 0.7874 0.4064)
			(end 0.7874 -0.4064)
			(stroke
				(width 0.1524)
				(type default)
			)
			(layer "B.SilkS")
		)
		(fp_line
			(start -0.7874 -0.4064)
			(end -0.7874 0.4064)
			(stroke
				(width 0.1524)
				(type default)
			)
			(layer "B.SilkS")
		)
		(fp_line
			(start 0.7874 -0.4064)
			(end -0.7874 -0.4064)
			(stroke
				(width 0.1524)
				(type default)
			)
			(layer "B.SilkS")
		)
		(fp_line
			(start -0.67945 0.3048)
			(end -0.120396 0.3048)
			(stroke
				(width 0.1)
				(type default)
			)
			(layer "B.Fab")
		)
		(fp_line
			(start -0.120396 0.3048)
			(end -0.120396 0.2794)
			(stroke
				(width 0.1)
				(type default)
			)
			(layer "B.Fab")
		)
		(fp_line
			(start 0.12065 0.3048)
			(end 0.67945 0.3048)
			(stroke
				(width 0.1)
				(type default)
			)
			(layer "B.Fab")
		)
		(fp_line
			(start 0.67945 0.3048)
			(end 0.67945 -0.305054)
			(stroke
				(width 0.1)
				(type default)
			)
			(layer "B.Fab")
		)
		(fp_line
			(start -0.120396 0.2794)
			(end 0.12065 0.2794)
			(stroke
				(width 0.1)
				(type default)
			)
			(layer "B.Fab")
		)
		(fp_line
			(start 0.12065 0.2794)
			(end 0.12065 0.3048)
			(stroke
				(width 0.1)
				(type default)
			)
			(layer "B.Fab")
		)
		(fp_line
			(start -0.12065 -0.2794)
			(end -0.12065 -0.3048)
			(stroke
				(width 0.1)
				(type default)
			)
			(layer "B.Fab")
		)
		(fp_line
			(start 0.12065 -0.2794)
			(end -0.12065 -0.2794)
			(stroke
				(width 0.1)
				(type default)
			)
			(layer "B.Fab")
		)
		(fp_line
			(start -0.67945 -0.3048)
			(end -0.67945 0.3048)
			(stroke
				(width 0.1)
				(type default)
			)
			(layer "B.Fab")
		)
		(fp_line
			(start -0.12065 -0.3048)
			(end -0.67945 -0.3048)
			(stroke
				(width 0.1)
				(type default)
			)
			(layer "B.Fab")
		)
		(fp_line
			(start 0.12065 -0.305054)
			(end 0.12065 -0.2794)
			(stroke
				(width 0.1)
				(type default)
			)
			(layer "B.Fab")
		)
		(fp_line
			(start 0.67945 -0.305054)
			(end 0.12065 -0.305054)
			(stroke
				(width 0.1)
				(type default)
			)
			(layer "B.Fab")
		)
		(pad "1" smd circle
			(at 0.40005 0 90)
			(size 0 0)
			(layers "B.Cu" "B.Mask" "B.Paste")
			(net "P3V3_AND")
		)
		(pad "2" smd circle
			(at -0.40005 0 90)
			(size 0 0)
			(layers "B.Cu" "B.Mask" "B.Paste")
			(net "GND")
		)
	)
	(footprint ""
		(layer "B.Cu")
		(at 108.7374 -44.3484 -90)
		(property "Reference" "PD18"
			(at 3.87477 -0.9398 0)
			(unlocked yes)
			(layer "B.SilkS")
			(effects
				(font
					(size 0.7874 0.5842)
					(thickness 0.1524)
				)
				(justify left mirror)
			)
		)
		(property "Value" ""
			(at 0 0 90)
			(layer "B.Fab")
			(effects
				(font
					(size 1.27 1.27)
				)
				(justify mirror)
			)
		)
		(duplicate_pad_numbers_are_jumpers no)
		(fp_line
			(start -2.032 0.7112)
			(end 1.651 0.7112)
			(stroke
				(width 0.1524)
				(type default)
			)
			(layer "B.SilkS")
		)
		(fp_line
			(start 1.651 0.7112)
			(end 1.651 -0.7112)
			(stroke
				(width 0.1524)
				(type default)
			)
			(layer "B.SilkS")
		)
		(fp_line
			(start -1.778 0.6858)
			(end -1.778 -0.6858)
			(stroke
				(width 0.1524)
				(type default)
			)
			(layer "B.SilkS")
		)
		(fp_line
			(start 0.299974 0.500126)
			(end -0.199898 0)
			(stroke
				(width 0.1524)
				(type default)
			)
			(layer "B.SilkS")
		)
		(fp_line
			(start -0.199898 0)
			(end 0.299974 -0.500126)
			(stroke
				(width 0.1524)
				(type default)
			)
			(layer "B.SilkS")
		)
		(fp_line
			(start -0.299974 -0.500126)
			(end -0.299974 0.500126)
			(stroke
				(width 0.1524)
				(type default)
			)
			(layer "B.SilkS")
		)
		(fp_line
			(start 0.299974 -0.500126)
			(end 0.299974 0.500126)
			(stroke
				(width 0.1524)
				(type default)
			)
			(layer "B.SilkS")
		)
		(fp_line
			(start -1.905 -0.6858)
			(end -1.905 0.6858)
			(stroke
				(width 0.1524)
				(type default)
			)
			(layer "B.SilkS")
		)
		(fp_line
			(start -1.651 -0.6858)
			(end -1.651 0.6858)
			(stroke
				(width 0.1524)
				(type default)
			)
			(layer "B.SilkS")
		)
		(fp_line
			(start -2.032 -0.7112)
			(end -2.032 0.7112)
			(stroke
				(width 0.1524)
				(type default)
			)
			(layer "B.SilkS")
		)
		(fp_line
			(start 1.651 -0.7112)
			(end -2.032 -0.7112)
			(stroke
				(width 0.1524)
				(type default)
			)
			(layer "B.SilkS")
		)
		(fp_line
			(start -0.899922 0.700024)
			(end 0.899922 0.700024)
			(stroke
				(width 0.1)
				(type default)
			)
			(layer "B.Fab")
		)
		(fp_line
			(start 0.899922 0.700024)
			(end 0.899922 0.175006)
			(stroke
				(width 0.1)
				(type default)
			)
			(layer "B.Fab")
		)
		(fp_line
			(start 0.299974 0.500126)
			(end -0.199898 0)
			(stroke
				(width 0.1)
				(type default)
			)
			(layer "B.Fab")
		)
		(fp_line
			(start -1.35001 0.175006)
			(end -0.899922 0.175006)
			(stroke
				(width 0.1)
				(type default)
			)
			(layer "B.Fab")
		)
		(fp_line
			(start -0.899922 0.175006)
			(end -0.899922 0.700024)
			(stroke
				(width 0.1)
				(type default)
			)
			(layer "B.Fab")
		)
		(fp_line
			(start 0.899922 0.175006)
			(end 1.35001 0.175006)
			(stroke
				(width 0.1)
				(type default)
			)
			(layer "B.Fab")
		)
		(fp_line
			(start 1.35001 0.175006)
			(end 1.35001 -0.225044)
			(stroke
				(width 0.1)
				(type default)
			)
			(layer "B.Fab")
		)
		(fp_line
			(start -0.199898 0)
			(end 0.299974 -0.500126)
			(stroke
				(width 0.1)
				(type default)
			)
			(layer "B.Fab")
		)
		(fp_line
			(start -1.35001 -0.225044)
			(end -1.35001 0.175006)
			(stroke
				(width 0.1)
				(type default)
			)
			(layer "B.Fab")
		)
		(fp_line
			(start -0.899922 -0.225044)
			(end -1.35001 -0.225044)
			(stroke
				(width 0.1)
				(type default)
			)
			(layer "B.Fab")
		)
		(fp_line
			(start 0.899922 -0.225044)
			(end 0.899922 -0.700024)
			(stroke
				(width 0.1)
				(type default)
			)
			(layer "B.Fab")
		)
		(fp_line
			(start 1.35001 -0.225044)
			(end 0.899922 -0.225044)
			(stroke
				(width 0.1)
				(type default)
			)
			(layer "B.Fab")
		)
		(fp_line
			(start -0.299974 -0.500126)
			(end -0.299974 0.500126)
			(stroke
				(width 0.1)
				(type default)
			)
			(layer "B.Fab")
		)
		(fp_line
			(start 0.299974 -0.500126)
			(end 0.299974 0.500126)
			(stroke
				(width 0.1)
				(type default)
			)
			(layer "B.Fab")
		)
		(fp_line
			(start -0.899922 -0.700024)
			(end -0.899922 -0.225044)
			(stroke
				(width 0.1)
				(type default)
			)
			(layer "B.Fab")
		)
		(fp_line
			(start 0.899922 -0.700024)
			(end -0.899922 -0.700024)
			(stroke
				(width 0.1)
				(type default)
			)
			(layer "B.Fab")
		)
		(fp_text user "+"
			(at 3.429 -0.19685 270)
			(unlocked yes)
			(layer "B.SilkS")
			(effects
				(font
					(size 1.905 1.4224)
					(thickness 0.1524)
				)
				(justify left mirror)
			)
		)
		(fp_text user "-"
			(at -1.8288 -0.24765 270)
			(unlocked yes)
			(layer "B.SilkS")
			(effects
				(font
					(size 1.905 1.4224)
					(thickness 0.1524)
				)
				(justify left mirror)
			)
		)
		(fp_text user "+"
			(at 2.794 -0.19685 270)
			(unlocked yes)
			(layer "B.Fab")
			(effects
				(font
					(size 1.905 1.4224)
					(thickness 0.1524)
				)
				(justify left mirror)
			)
		)
		(fp_text user "-"
			(at -1.8288 -0.24765 270)
			(unlocked yes)
			(layer "B.Fab")
			(effects
				(font
					(size 1.905 1.4224)
					(thickness 0.1524)
				)
				(justify left mirror)
			)
		)
		(pad "1" smd rect
			(at 1.0922 0 270)
			(size 0.8128 0.8636)
			(layers "B.Cu" "B.Mask" "B.Paste")
			(net "P52V_HS2_4287_GATE2_R")
		)
		(pad "2" smd rect
			(at -1.0922 0 90)
			(size 0.8128 0.8636)
			(layers "B.Cu" "B.Mask" "B.Paste")
			(net "P52V_HS2_GATE2_R1")
		)
	)
)
